(kicad_pcb
	(version 20260206)
	(generator "pcbnew")
	(generator_version "10.0")
	(general
		(thickness 1.21888)
		(legacy_teardrops no)
	)
	(paper "A4")
	(title_block
		(title "timecard-v8 — TimeCard-DC-V8_EXP.PcbDoc")
		(comment 1 "Time Appliance Project (Time Card) / footprints 213-221 of 288")
	)
	(layers
		(0 "F.Cu" signal "TOP")
		(4 "In1.Cu" signal "SGND")
		(6 "In2.Cu" signal "IN1")
		(8 "In3.Cu" signal "IN2")
		(10 "In4.Cu" signal "SGND1")
		(2 "B.Cu" signal "BOTTOM")
		(9 "F.Adhes" user "F.Adhesive")
		(11 "B.Adhes" user "B.Adhesive")
		(13 "F.Paste" user "Top Paste")
		(15 "B.Paste" user "Bottom Paste")
		(5 "F.SilkS" user "Top Overlay")
		(7 "B.SilkS" user "Bottom Overlay")
		(1 "F.Mask" user "Top Solder")
		(3 "B.Mask" user "Bottom Solder")
		(17 "Dwgs.User" user "User.Drawings")
		(19 "Cmts.User" user "User.Comments")
		(21 "Eco1.User" user "User.Eco1")
		(23 "Eco2.User" user "User.Eco2")
		(25 "Edge.Cuts" user)
		(27 "Margin" user)
		(31 "F.CrtYd" user "Top Courtyard")
		(29 "B.CrtYd" user "Bottom Courtyard")
		(35 "F.Fab" user "Top Component Center")
		(33 "B.Fab" user "Bottom Component Center")
	)
	(footprint "Vault:RESC1005X40X25LL05T05"
		(layer "F.Cu")
		(at 232.7261 117.0162 -90)
		(property "Reference" "R65"
			(at 0.3286 1.226931 270)
			(unlocked yes)
			(layer "F.SilkS")
			(effects
				(font
					(size 0.762 0.762)
					(thickness 0.2286)
				)
			)
		)
		(property "Value" "0_1%_0402"
			(at -2.579871 6.66536 180)
			(unlocked yes)
			(layer "F.SilkS")
			(hide yes)
			(effects
				(font
					(size 0.762 0.762)
					(thickness 0.2286)
				)
			)
		)
		(sheetname "POWER")
		(sheetfile "POWER.kicad_sch")
		(duplicate_pad_numbers_are_jumpers no)
		(pad "1" smd rect
			(at -0.4 0)
			(size 0.45 0.45)
			(layers "F.Cu" "F.Mask" "F.Paste")
			(net "NetR65_1")
		)
		(pad "2" smd rect
			(at 0.4 0)
			(size 0.45 0.45)
			(layers "F.Cu" "F.Mask" "F.Paste")
			(net "+3.3V")
		)
	)
	(footprint "SA53:SolderSocket"
		(layer "F.Cu")
		(at 99.3261 115.2162 90)
		(property "Reference" "SKT6"
			(at -0.126921 -6.9714 0)
			(unlocked yes)
			(layer "F.SilkS")
			(effects
				(font
					(size 0.762 0.762)
					(thickness 0.2286)
				)
			)
		)
		(property "Value" "0332-0-43-80-18-27-10-0"
			(at -2.910071 16.1362 0)
			(unlocked yes)
			(layer "F.SilkS")
			(hide yes)
			(effects
				(font
					(size 0.762 0.762)
					(thickness 0.2286)
				)
			)
		)
		(sheetname "MAC")
		(sheetfile "MAC.kicad_sch")
		(duplicate_pad_numbers_are_jumpers no)
		(pad "1" thru_hole circle
			(at 0 0 90)
			(size 2.54 2.54)
			(drill 2.0066)
			(layers "*.Cu" "*.Mask")
			(remove_unused_layers no)
			(net "GND")
			(thermal_bridge_angle 90)
		)
	)
	(footprint "Vault:FP-GRM31C-0_2-e0_3_0_8-IPC_C"
		(layer "F.Cu")
		(at 214.1261 119.5162 90)
		(property "Reference" "C77"
			(at 0.46924 -2.601729 90)
			(unlocked yes)
			(layer "F.SilkS")
			(effects
				(font
					(size 0.762 0.762)
					(thickness 0.2286)
				)
			)
		)
		(property "Value" "4.7uF_50V_1206"
			(at 8.594615 2.719551 90)
			(unlocked yes)
			(layer "F.SilkS")
			(hide yes)
			(effects
				(font
					(size 0.762 0.762)
					(thickness 0.2286)
				)
			)
		)
		(sheetname "POWER")
		(sheetfile "POWER.kicad_sch")
		(duplicate_pad_numbers_are_jumpers no)
		(fp_line
			(start -0.39847 -0.9)
			(end 0.39846 -0.9)
			(stroke
				(width 0.2)
				(type solid)
			)
			(layer "F.SilkS")
		)
		(fp_line
			(start -0.39847 0.9)
			(end 0.39846 0.9)
			(stroke
				(width 0.2)
				(type solid)
			)
			(layer "F.SilkS")
		)
		(fp_line
			(start 1.9531 -1)
			(end 1.9531 1)
			(stroke
				(width 0.2)
				(type solid)
			)
			(layer "F.CrtYd")
		)
		(fp_line
			(start -1.9531 -1)
			(end 1.9531 -1)
			(stroke
				(width 0.2)
				(type solid)
			)
			(layer "F.CrtYd")
		)
		(fp_line
			(start -1.9531 -1)
			(end -1.9531 1)
			(stroke
				(width 0.2)
				(type solid)
			)
			(layer "F.CrtYd")
		)
		(fp_line
			(start -1.9531 1)
			(end 1.9531 1)
			(stroke
				(width 0.2)
				(type solid)
			)
			(layer "F.CrtYd")
		)
		(fp_line
			(start 1.9531 -1)
			(end 1.9531 1)
			(stroke
				(width 0.2)
				(type solid)
			)
			(layer "F.Fab")
		)
		(fp_line
			(start -1.9531 -1)
			(end 1.9531 -1)
			(stroke
				(width 0.2)
				(type solid)
			)
			(layer "F.Fab")
		)
		(fp_line
			(start -1.9531 -1)
			(end -1.9531 1)
			(stroke
				(width 0.2)
				(type solid)
			)
			(layer "F.Fab")
		)
		(fp_line
			(start 0 -0.5)
			(end 0 0.5)
			(stroke
				(width 0.1)
				(type solid)
			)
			(layer "F.Fab")
		)
		(fp_line
			(start -0.5 0)
			(end 0.5 0)
			(stroke
				(width 0.1)
				(type solid)
			)
			(layer "F.Fab")
		)
		(fp_line
			(start -1.9531 1)
			(end 1.9531 1)
			(stroke
				(width 0.2)
				(type solid)
			)
			(layer "F.Fab")
		)
		(fp_text user "${REFERENCE}"
			(at -0.00002 0.09601 90)
			(unlocked yes)
			(layer "F.Fab")
			(effects
				(font
					(face "Arial")
					(size 0.63 0.63)
					(thickness 0.1)
				)
				(justify left bottom)
			)
		)
		(pad "1" smd rect
			(at -1.27578 0 90)
			(size 1.15464 1.7062)
			(layers "F.Cu" "F.Mask" "F.Paste")
			(net "+12V")
			(solder_mask_margin 0)
			(solder_paste_margin 0)
		)
		(pad "2" smd rect
			(at 1.27578 0 90)
			(size 1.15464 1.7062)
			(layers "F.Cu" "F.Mask" "F.Paste")
			(net "GND")
			(solder_mask_margin 0)
			(solder_paste_margin 0)
		)
	)
	(footprint "Vault:RESC1005X40X25LL05T05"
		(layer "F.Cu")
		(at 203.3261 82.8162 180)
		(property "Reference" "R62"
			(at -0.0286 1.573069 0)
			(unlocked yes)
			(layer "F.SilkS")
			(effects
				(font
					(size 0.762 0.762)
					(thickness 0.2286)
				)
			)
		)
		(property "Value" "0_1%_0402"
			(at -2.579871 6.66536 90)
			(unlocked yes)
			(layer "F.SilkS")
			(hide yes)
			(effects
				(font
					(size 0.762 0.762)
					(thickness 0.2286)
				)
			)
		)
		(sheetname "POWER")
		(sheetfile "POWER.kicad_sch")
		(duplicate_pad_numbers_are_jumpers no)
		(pad "1" smd rect
			(at -0.4 0 270)
			(size 0.45 0.45)
			(layers "F.Cu" "F.Mask" "F.Paste")
			(net "NetR62_1")
		)
		(pad "2" smd rect
			(at 0.4 0 270)
			(size 0.45 0.45)
			(layers "F.Cu" "F.Mask" "F.Paste")
			(net "GND")
		)
	)
	(footprint "Vault:RESC1005X40X25LL05T05"
		(layer "F.Cu")
		(at 206.1261 108.2162)
		(property "Reference" "R2"
			(at -5.21855 -0.039955 0)
			(unlocked yes)
			(layer "F.SilkS")
			(effects
				(font
					(size 0.762 0.762)
					(thickness 0.2286)
				)
				(justify left bottom)
			)
		)
		(property "Value" "4.7K_0402"
			(at 17.0993 9.461245 0)
			(unlocked yes)
			(layer "F.SilkS")
			(hide yes)
			(effects
				(font
					(size 0.762 0.762)
					(thickness 0.2286)
				)
				(justify left bottom)
			)
		)
		(sheetname "POWER")
		(sheetfile "POWER.kicad_sch")
		(duplicate_pad_numbers_are_jumpers no)
		(pad "1" smd rect
			(at -0.4 0 90)
			(size 0.45 0.45)
			(layers "F.Cu" "F.Mask" "F.Paste")
			(net "+12V")
		)
		(pad "2" smd rect
			(at 0.4 0 90)
			(size 0.45 0.45)
			(layers "F.Cu" "F.Mask" "F.Paste")
			(net "NetR2_2")
		)
	)
	(footprint "Vault:FP-CL180-IPC_C"
		(layer "F.Cu")
		(at 213.4261 129.1162 -90)
		(property "Reference" "C72"
			(at 2.3286 0.126931 270)
			(unlocked yes)
			(layer "F.SilkS")
			(effects
				(font
					(size 0.762 0.762)
					(thickness 0.2286)
				)
			)
		)
		(property "Value" "DNI_1nF_50V_0402"
			(at -2.440151 11.38813 180)
			(unlocked yes)
			(layer "F.SilkS")
			(hide yes)
			(effects
				(font
					(size 0.762 0.762)
					(thickness 0.2286)
				)
			)
		)
		(sheetname "POWER")
		(sheetfile "POWER.kicad_sch")
		(duplicate_pad_numbers_are_jumpers no)
		(fp_line
			(start 0.63624 0.675)
			(end -0.63624 0.675)
			(stroke
				(width 0.2)
				(type solid)
			)
			(layer "F.SilkS")
		)
		(fp_line
			(start 0.63624 -0.675)
			(end -0.63624 -0.675)
			(stroke
				(width 0.2)
				(type solid)
			)
			(layer "F.SilkS")
		)
		(fp_line
			(start -0.73624 0.375)
			(end -0.73624 -0.375)
			(stroke
				(width 0.2)
				(type solid)
			)
			(layer "F.CrtYd")
		)
		(fp_line
			(start 0.73624 0.375)
			(end -0.73624 0.375)
			(stroke
				(width 0.2)
				(type solid)
			)
			(layer "F.CrtYd")
		)
		(fp_line
			(start 0.73624 0.375)
			(end 0.73624 -0.375)
			(stroke
				(width 0.2)
				(type solid)
			)
			(layer "F.CrtYd")
		)
		(fp_line
			(start 0.73624 -0.375)
			(end -0.73624 -0.375)
			(stroke
				(width 0.2)
				(type solid)
			)
			(layer "F.CrtYd")
		)
		(fp_line
			(start 0 0.5)
			(end 0 -0.5)
			(stroke
				(width 0.1)
				(type solid)
			)
			(layer "F.Fab")
		)
		(fp_line
			(start 0 0.5)
			(end 0 -0.5)
			(stroke
				(width 0.1)
				(type solid)
			)
			(layer "F.Fab")
		)
		(fp_line
			(start -0.73624 0.375)
			(end -0.73624 -0.375)
			(stroke
				(width 0.2)
				(type solid)
			)
			(layer "F.Fab")
		)
		(fp_line
			(start 0.73624 0.375)
			(end -0.73624 0.375)
			(stroke
				(width 0.2)
				(type solid)
			)
			(layer "F.Fab")
		)
		(fp_line
			(start 0.73624 0.375)
			(end 0.73624 -0.375)
			(stroke
				(width 0.2)
				(type solid)
			)
			(layer "F.Fab")
		)
		(fp_line
			(start 0.5 0)
			(end -0.5 0)
			(stroke
				(width 0.1)
				(type solid)
			)
			(layer "F.Fab")
		)
		(fp_line
			(start 0.5 0)
			(end -0.5 0)
			(stroke
				(width 0.1)
				(type solid)
			)
			(layer "F.Fab")
		)
		(fp_line
			(start 0.73624 -0.375)
			(end -0.73624 -0.375)
			(stroke
				(width 0.2)
				(type solid)
			)
			(layer "F.Fab")
		)
		(fp_text user "${REFERENCE}"
			(at 0 0.28425 270)
			(unlocked yes)
			(layer "F.Fab")
			(effects
				(font
					(face "Arial")
					(size 0.63 0.63)
					(thickness 0.1)
				)
				(justify left bottom)
			)
		)
		(pad "1" smd rect
			(at -0.37856 0 270)
			(size 0.51535 0.47247)
			(layers "F.Cu" "F.Mask" "F.Paste")
			(net "NetC72_1")
			(solder_mask_margin 0)
			(solder_paste_margin 0)
		)
		(pad "2" smd rect
			(at 0.37856 0 270)
			(size 0.51535 0.47247)
			(layers "F.Cu" "F.Mask" "F.Paste")
			(net "GND")
			(solder_mask_margin 0)
			(solder_paste_margin 0)
		)
	)
	(footprint "Vault:RESC1005X40X25LL05T05"
		(layer "F.Cu")
		(at 206.1261 107.3162)
		(property "Reference" "R3"
			(at -5.11855 -0.239955 0)
			(unlocked yes)
			(layer "F.SilkS")
			(effects
				(font
					(size 0.762 0.762)
					(thickness 0.2286)
				)
				(justify left bottom)
			)
		)
		(property "Value" "4.7K_0402"
			(at 26.9821 21.663245 0)
			(unlocked yes)
			(layer "F.SilkS")
			(hide yes)
			(effects
				(font
					(size 0.762 0.762)
					(thickness 0.2286)
				)
				(justify left bottom)
			)
		)
		(sheetname "POWER")
		(sheetfile "POWER.kicad_sch")
		(duplicate_pad_numbers_are_jumpers no)
		(pad "1" smd rect
			(at -0.4 0 90)
			(size 0.45 0.45)
			(layers "F.Cu" "F.Mask" "F.Paste")
			(net "+3.3V")
		)
		(pad "2" smd rect
			(at 0.4 0 90)
			(size 0.45 0.45)
			(layers "F.Cu" "F.Mask" "F.Paste")
			(net "NetR3_2")
		)
	)
	(footprint "Vault:RESC1608X55X30LL15T20"
		(layer "F.Cu")
		(at 179.6261 90.0786 180)
		(property "Reference" "R37"
			(at 2.1714 -0.164531 0)
			(unlocked yes)
			(layer "F.SilkS")
			(effects
				(font
					(size 0.762 0.762)
					(thickness 0.2286)
				)
			)
		)
		(property "Value" "10K"
			(at -2.630671 1.76468 90)
			(unlocked yes)
			(layer "F.SilkS")
			(hide yes)
			(effects
				(font
					(size 0.762 0.762)
					(thickness 0.2286)
				)
			)
		)
		(sheetname "GPS_IMU_SENSORS")
		(sheetfile "GPS_IMU_SENSORS.kicad_sch")
		(duplicate_pad_numbers_are_jumpers no)
		(pad "1" smd rect
			(at -0.575 0 270)
			(size 0.85 0.75)
			(layers "F.Cu" "F.Mask" "F.Paste")
			(net "EXT_EEPROM_WP")
		)
		(pad "2" smd rect
			(at 0.575 0 270)
			(size 0.85 0.75)
			(layers "F.Cu" "F.Mask" "F.Paste")
			(net "+3.3V")
		)
	)
	(footprint "Vault:RESC1005X40X25NL10T10"
		(layer "F.Cu")
		(at 202.8761 122.6662)
		(property "Reference" "R78"
			(at -3.1214 4.176931 0)
			(unlocked yes)
			(layer "F.SilkS")
			(effects
				(font
					(size 0.762 0.762)
					(thickness 0.2286)
				)
			)
		)
		(property "Value" "787_1%_0402"
			(at -2.884671 8.036475 270)
			(unlocked yes)
			(layer "F.SilkS")
			(hide yes)
			(effects
				(font
					(size 0.762 0.762)
					(thickness 0.2286)
				)
			)
		)
		(sheetname "POWER")
		(sheetfile "POWER.kicad_sch")
		(duplicate_pad_numbers_are_jumpers no)
		(pad "1" smd rect
			(at -0.425 0 90)
			(size 0.6 0.65)
			(layers "F.Cu" "F.Mask" "F.Paste")
			(net "GND")
		)
		(pad "2" smd rect
			(at 0.425 0 90)
			(size 0.6 0.65)
			(layers "F.Cu" "F.Mask" "F.Paste")
			(net "P3V3_FB")
		)
	)
)
